# S9S_MB_2U (Grand Teton) — schematic netlist excerpt (pin names and nets, part order shuffled) for the footprints in the layout excerpt that follows; sources: Cadence DE-HDL packaged netlist, KiCad conversion of 03242023_DA0F0TMBIJ0_F0T_Motherboard_J_brd_V01_OCP.brd

R3561  Q_RES  0 5% CHIP  pkg 0402LF  page 172 : A = P12V_SCM_ADC_ALERT_R ; B = P12V_SCM_ADC_ALERT
R482  Q_RES  0 5% CHIP  pkg 0402LF  page 239 : A = JTAG_DBP_PREQ_N ; B = JTAG_DBP_PREQ_R_N

(kicad_pcb
	(version 20260206)
	(generator "pcbnew")
	(generator_version "10.0")
	(general
		(thickness 1.6)
		(legacy_teardrops no)
	)
	(paper "A4")
	(title_block
		(title "03242023_DA0F0TMBIJ0_F0T_Motherboard_J_brd_V01_OCP.brd")
		(comment 1 "Grand Teton / footprints 1594-1595 of 6105")
	)
	(layers
		(0 "F.Cu" signal "TOP")
		(4 "In1.Cu" signal "GND")
		(6 "In2.Cu" signal "IN1")
		(8 "In3.Cu" signal "GND1")
		(10 "In4.Cu" signal "IN2")
		(12 "In5.Cu" signal "GND2")
		(14 "In6.Cu" signal "IN3")
		(16 "In7.Cu" signal "GND3")
		(18 "In8.Cu" signal "VCC")
		(20 "In9.Cu" signal "VCC1")
		(22 "In10.Cu" signal "GND4")
		(24 "In11.Cu" signal "IN4")
		(26 "In12.Cu" signal "GND5")
		(28 "In13.Cu" signal "IN5")
		(30 "In14.Cu" signal "GND6")
		(32 "In15.Cu" signal "IN6")
		(34 "In16.Cu" signal "GND7")
		(2 "B.Cu" signal "BOTTOM")
		(9 "F.Adhes" user "F.Adhesive")
		(11 "B.Adhes" user "B.Adhesive")
		(13 "F.Paste" user "Package Geometry/Pastemask Top")
		(15 "B.Paste" user "Package Geometry/Pastemask Bottom")
		(5 "F.SilkS" user "Ref Des/Silkscreen Top")
		(7 "B.SilkS" user "Ref Des/Silkscreen Bottom")
		(1 "F.Mask" user "Board Geometry/Soldermask Top")
		(3 "B.Mask" user "Board Geometry/Soldermask Bottom")
		(17 "Dwgs.User" user "User.Drawings")
		(19 "Cmts.User" user "User.Comments")
		(21 "Eco1.User" user "User.Eco1")
		(23 "Eco2.User" user "User.Eco2")
		(25 "Edge.Cuts" user "Board Geometry/Outline")
		(27 "Margin" user)
		(31 "F.CrtYd" user "Package Geometry/Place Bound Top")
		(29 "B.CrtYd" user "Package Geometry/Place Bound Bottom")
		(35 "F.Fab" user "Ref Des/Assembly Top")
		(33 "B.Fab" user "Ref Des/Assembly Bottom")
	)
	(footprint ""
		(layer "F.Cu")
		(at 369.259358 -92.962984 90)
		(property "Reference" "R482"
			(at 0 0 90)
			(layer "F.SilkS")
			(hide yes)
			(effects
				(font
					(size 1.27 1.27)
				)
			)
		)
		(property "Value" ""
			(at 0 0 90)
			(layer "F.Fab")
			(effects
				(font
					(size 1.27 1.27)
				)
			)
		)
		(duplicate_pad_numbers_are_jumpers no)
		(fp_line
			(start 0.7874 -0.4064)
			(end 0.7874 0.4064)
			(stroke
				(width 0.1524)
				(type default)
			)
			(layer "F.SilkS")
		)
		(fp_line
			(start -0.7874 -0.4064)
			(end 0.7874 -0.4064)
			(stroke
				(width 0.1524)
				(type default)
			)
			(layer "F.SilkS")
		)
		(fp_line
			(start 0.7874 0.4064)
			(end -0.7874 0.4064)
			(stroke
				(width 0.1524)
				(type default)
			)
			(layer "F.SilkS")
		)
		(fp_line
			(start -0.7874 0.4064)
			(end -0.7874 -0.4064)
			(stroke
				(width 0.1524)
				(type default)
			)
			(layer "F.SilkS")
		)
		(fp_line
			(start -0.12065 -0.305054)
			(end -0.12065 -0.2794)
			(stroke
				(width 0.1)
				(type default)
			)
			(layer "F.Fab")
		)
		(fp_line
			(start -0.67945 -0.305054)
			(end -0.12065 -0.305054)
			(stroke
				(width 0.1)
				(type default)
			)
			(layer "F.Fab")
		)
		(fp_line
			(start 0.67945 -0.3048)
			(end 0.67945 0.3048)
			(stroke
				(width 0.1)
				(type default)
			)
			(layer "F.Fab")
		)
		(fp_line
			(start 0.12065 -0.3048)
			(end 0.67945 -0.3048)
			(stroke
				(width 0.1)
				(type default)
			)
			(layer "F.Fab")
		)
		(fp_line
			(start 0.12065 -0.2794)
			(end 0.12065 -0.3048)
			(stroke
				(width 0.1)
				(type default)
			)
			(layer "F.Fab")
		)
		(fp_line
			(start -0.12065 -0.2794)
			(end 0.12065 -0.2794)
			(stroke
				(width 0.1)
				(type default)
			)
			(layer "F.Fab")
		)
		(fp_line
			(start 0.120396 0.2794)
			(end -0.12065 0.2794)
			(stroke
				(width 0.1)
				(type default)
			)
			(layer "F.Fab")
		)
		(fp_line
			(start -0.12065 0.2794)
			(end -0.12065 0.3048)
			(stroke
				(width 0.1)
				(type default)
			)
			(layer "F.Fab")
		)
		(fp_line
			(start 0.67945 0.3048)
			(end 0.120396 0.3048)
			(stroke
				(width 0.1)
				(type default)
			)
			(layer "F.Fab")
		)
		(fp_line
			(start 0.120396 0.3048)
			(end 0.120396 0.2794)
			(stroke
				(width 0.1)
				(type default)
			)
			(layer "F.Fab")
		)
		(fp_line
			(start -0.12065 0.3048)
			(end -0.67945 0.3048)
			(stroke
				(width 0.1)
				(type default)
			)
			(layer "F.Fab")
		)
		(fp_line
			(start -0.67945 0.3048)
			(end -0.67945 -0.305054)
			(stroke
				(width 0.1)
				(type default)
			)
			(layer "F.Fab")
		)
		(pad "1" smd circle
			(at -0.40005 0 90)
			(size 0 0)
			(layers "F.Cu" "F.Mask" "F.Paste")
			(net "JTAG_DBP_PREQ_N")
		)
		(pad "2" smd circle
			(at 0.40005 0 90)
			(size 0 0)
			(layers "F.Cu" "F.Mask" "F.Paste")
			(net "JTAG_DBP_PREQ_R_N")
		)
	)
	(footprint ""
		(layer "F.Cu")
		(at 212.118956 -30.276292 -90)
		(property "Reference" "R3561"
			(at 0 0 270)
			(layer "F.SilkS")
			(hide yes)
			(effects
				(font
					(size 1.27 1.27)
				)
			)
		)
		(property "Value" ""
			(at 0 0 270)
			(layer "F.Fab")
			(effects
				(font
					(size 1.27 1.27)
				)
			)
		)
		(duplicate_pad_numbers_are_jumpers no)
		(fp_line
			(start -0.7874 0.4064)
			(end -0.7874 -0.4064)
			(stroke
				(width 0.1524)
				(type default)
			)
			(layer "F.SilkS")
		)
		(fp_line
			(start 0.7874 0.4064)
			(end -0.7874 0.4064)
			(stroke
				(width 0.1524)
				(type default)
			)
			(layer "F.SilkS")
		)
		(fp_line
			(start -0.7874 -0.4064)
			(end 0.7874 -0.4064)
			(stroke
				(width 0.1524)
				(type default)
			)
			(layer "F.SilkS")
		)
		(fp_line
			(start 0.7874 -0.4064)
			(end 0.7874 0.4064)
			(stroke
				(width 0.1524)
				(type default)
			)
			(layer "F.SilkS")
		)
		(fp_line
			(start -0.67945 0.3048)
			(end -0.67945 -0.305054)
			(stroke
				(width 0.1)
				(type default)
			)
			(layer "F.Fab")
		)
		(fp_line
			(start -0.12065 0.3048)
			(end -0.67945 0.3048)
			(stroke
				(width 0.1)
				(type default)
			)
			(layer "F.Fab")
		)
		(fp_line
			(start 0.120396 0.3048)
			(end 0.120396 0.2794)
			(stroke
				(width 0.1)
				(type default)
			)
			(layer "F.Fab")
		)
		(fp_line
			(start 0.67945 0.3048)
			(end 0.120396 0.3048)
			(stroke
				(width 0.1)
				(type default)
			)
			(layer "F.Fab")
		)
		(fp_line
			(start -0.12065 0.2794)
			(end -0.12065 0.3048)
			(stroke
				(width 0.1)
				(type default)
			)
			(layer "F.Fab")
		)
		(fp_line
			(start 0.120396 0.2794)
			(end -0.12065 0.2794)
			(stroke
				(width 0.1)
				(type default)
			)
			(layer "F.Fab")
		)
		(fp_line
			(start -0.12065 -0.2794)
			(end 0.12065 -0.2794)
			(stroke
				(width 0.1)
				(type default)
			)
			(layer "F.Fab")
		)
		(fp_line
			(start 0.12065 -0.2794)
			(end 0.12065 -0.3048)
			(stroke
				(width 0.1)
				(type default)
			)
			(layer "F.Fab")
		)
		(fp_line
			(start 0.12065 -0.3048)
			(end 0.67945 -0.3048)
			(stroke
				(width 0.1)
				(type default)
			)
			(layer "F.Fab")
		)
		(fp_line
			(start 0.67945 -0.3048)
			(end 0.67945 0.3048)
			(stroke
				(width 0.1)
				(type default)
			)
			(layer "F.Fab")
		)
		(fp_line
			(start -0.67945 -0.305054)
			(end -0.12065 -0.305054)
			(stroke
				(width 0.1)
				(type default)
			)
			(layer "F.Fab")
		)
		(fp_line
			(start -0.12065 -0.305054)
			(end -0.12065 -0.2794)
			(stroke
				(width 0.1)
				(type default)
			)
			(layer "F.Fab")
		)
		(pad "1" smd circle
			(at -0.40005 0 270)
			(size 0 0)
			(layers "F.Cu" "F.Mask" "F.Paste")
			(net "P12V_SCM_ADC_ALERT_R")
		)
		(pad "2" smd circle
			(at 0.40005 0 270)
			(size 0 0)
			(layers "F.Cu" "F.Mask" "F.Paste")
			(net "P12V_SCM_ADC_ALERT")
		)
	)
)
